# S9S_MB_2U (Grand Teton) — schematic netlist excerpt (pin names and nets, part order shuffled) for the footprints in the layout excerpt that follows; sources: Cadence DE-HDL packaged netlist, KiCad conversion of 03242023_DA0F0TMBIJ0_F0T_Motherboard_J_brd_V01_OCP.brd

J6  SCONN288_ADR50017P087CC  SCONN288_ADR50017-P087CC IO  pkg DDR288S_1-1VXB  page 87
  VIN_BULK0  = P12V_S3_AUX_CPU0_NVDIMM
  RFU0  = TP_CHC_CPU0_DIMM2_FRU_0
  VIN_MGMT  = P3V3_AUX
  HSCL  = I3C_SPD_DDRABCD_CPU0_LVC1_SCL_5
  HSDA  = I3C_SPD_DDRABCD_CPU0_LVC1_SDA
  VSS0  = GND
  DQ0_A  = M_C_CPU0_SA_DQ<0>
  VSS1  = GND
  DQ1_A  = M_C_CPU0_SA_DQ<1>
  VSS2  = GND
  DQS0_A_T  = M_C_CPU0_SA_DQS_DP<0>
  DQS0_A_C  = M_C_CPU0_SA_DQS_DN<0>
  VSS3  = GND
  DQ4_A  = M_C_CPU0_SA_DQ<4>
  VSS4  = GND
  DQ5_A  = M_C_CPU0_SA_DQ<5>
  VSS5  = GND
  DQ8_A  = M_C_CPU0_SA_DQ<8>
  VSS6  = GND
  DQ9_A  = M_C_CPU0_SA_DQ<9>
  VSS7  = GND
  DQS1_A_T  = M_C_CPU0_SA_DQS_DP<1>
  DQS1_A_C  = M_C_CPU0_SA_DQS_DN<1>
  VSS8  = GND
  DQ12_A  = M_C_CPU0_SA_DQ<12>
  VSS9  = GND
  DQ13_A  = M_C_CPU0_SA_DQ<13>
  VSS10  = GND
  DQ16_A  = M_C_CPU0_SA_DQ<16>
  VSS11  = GND
  DQ17_A  = M_C_CPU0_SA_DQ<17>
  VSS12  = GND
  DQS2_A_T  = M_C_CPU0_SA_DQS_DP<2>
  DQS2_A_C  = M_C_CPU0_SA_DQS_DN<2>
  VSS13  = GND
  DQ20_A  = M_C_CPU0_SA_DQ<20>
  VSS14  = GND
  DQ21_A  = M_C_CPU0_SA_DQ<21>
  VSS15  = GND
  DQ24_A  = M_C_CPU0_SA_DQ<24>
  VSS16  = GND
  DQ25_A  = M_C_CPU0_SA_DQ<25>
  VSS17  = GND
  DQS3_A_T  = M_C_CPU0_SA_DQS_DP<3>
  DQS3_A_C  = M_C_CPU0_SA_DQS_DN<3>
  VSS18  = GND
  DQ28_A  = M_C_CPU0_SA_DQ<28>
  VSS19  = GND
  DQ29_A  = M_C_CPU0_SA_DQ<29>
  VSS20  = GND
  CB0_A  = M_C_CPU0_SA_CB<0>
  VSS21  = GND
  CB1_A  = M_C_CPU0_SA_CB<1>
  VSS22  = GND
  DQS4_A_T  = M_C_CPU0_SA_DQS_DP<4>
  DQS4_A_C  = M_C_CPU0_SA_DQS_DN<4>
  VSS23  = GND
  CB4_A  = M_C_CPU0_SA_CB<4>
  VSS24  = GND
  CB5_A  = M_C_CPU0_SA_CB<5>
  VSS25  = GND
  ALERT_N  = M_C_CPU0_ALERT_N
  VSS26  = GND
  CS0_A_N  = M_C_CPU0_SA_CS_N<2>
  VSS27  = GND
  CA0_A  = M_C_CPU0_SA_CA<0>
  VSS28  = GND
  CA2_A  = M_C_CPU0_SA_CA<2>
  VSS29  = GND
  CA4_A  = M_C_CPU0_SA_CA<4>
  VSS30  = GND
  CA6_A  = M_C_CPU0_SA_CA<6>
  VSS31  = GND
  PAR_A  = M_C_CPU0_SA_PAR
  VSS32  = GND
  CA0_B  = M_C_CPU0_SB_CA<0>
  VSS33  = GND
  CA2_B  = M_C_CPU0_SB_CA<2>
  VSS34  = GND
  CA4_B  = M_C_CPU0_SB_CA<4>
  VSS35  = GND
  CA6_B  = M_C_CPU0_SB_CA<6>
  VSS36  = GND
  CS0_B_N  = M_C_CPU0_SB_CS_N<2>
  VSS37  = GND
  \lbd||rsp_a_n\  = M_C_CPU0_SA_RSP<1>
  \lbs||rsp_b_n\  = M_C_CPU0_SB_RSP<1>
  VSS38  = GND
  CB4_B  = M_C_CPU0_SB_CB<4>
  VSS39  = GND
  CB5_B  = M_C_CPU0_SB_CB<5>
  VSS40  = GND
  \dqs9_b_t||tdqs9_b_t||dbi4_b_n\  = M_C_CPU0_SB_DQS_DP<9>
  \dqs9_b_c||tdqs9_b_c\  = M_C_CPU0_SB_DQS_DN<9>
  VSS41  = GND
  CB0_B  = M_C_CPU0_SB_CB<0>
  VSS42  = GND
  CB1_B  = M_C_CPU0_SB_CB<1>
  VSS43  = GND
  DQ0_B  = M_C_CPU0_SB_DQ<0>
  VSS44  = GND
  DQ1_B  = M_C_CPU0_SB_DQ<1>
  VSS45  = GND
  DQS0_B_T  = M_C_CPU0_SB_DQS_DP<0>
  DQS0_B_C  = M_C_CPU0_SB_DQS_DN<0>
  VSS46  = GND
  DQ4_B  = M_C_CPU0_SB_DQ<4>
  VSS47  = GND
  DQ5_B  = M_C_CPU0_SB_DQ<5>
  VSS48  = GND
  DQ8_B  = M_C_CPU0_SB_DQ<8>
  VSS49  = GND
  DQ9_B  = M_C_CPU0_SB_DQ<9>
  VSS50  = GND
  DQS1_B_T  = M_C_CPU0_SB_DQS_DP<1>
  DQS1_B_C  = M_C_CPU0_SB_DQS_DN<1>
  VSS51  = GND
  DQ12_B  = M_C_CPU0_SB_DQ<12>
  VSS52  = GND
  DQ13_B  = M_C_CPU0_SB_DQ<13>
  VSS53  = GND
  DQ16_B  = M_C_CPU0_SB_DQ<16>
  VSS54  = GND
  DQ17_B  = M_C_CPU0_SB_DQ<17>
  VSS55  = GND
  DQS2_B_T  = M_C_CPU0_SB_DQS_DP<2>
  DQS2_B_C  = M_C_CPU0_SB_DQS_DN<2>
  VSS56  = GND
  DQ20_B  = M_C_CPU0_SB_DQ<20>
  VSS57  = GND
  DQ21_B  = M_C_CPU0_SB_DQ<21>
  VSS58  = GND
  DQ24_B  = M_C_CPU0_SB_DQ<24>
  VSS59  = GND
  DQ25_B  = M_C_CPU0_SB_DQ<25>
  VSS60  = GND
  DQS3_B_T  = M_C_CPU0_SB_DQS_DP<3>
  DQS3_B_C  = M_C_CPU0_SB_DQS_DN<3>
  VSS61  = GND
  DQ28_B  = M_C_CPU0_SB_DQ<28>
  VSS62  = GND
  DQ29_B  = M_C_CPU0_SB_DQ<29>
  VSS63  = GND
  RFU1  = TP_CHC_CPU0_DIMM2_FRU_1
  VIN_BULK1  = P12V_S3_AUX_CPU0_NVDIMM
  VIN_BULK2  = P12V_S3_AUX_CPU0_NVDIMM
  \pwr_good||fail_n\  = PWRGD_CHC_CPU0_DIMM2
  HSA  = PD_CHC_CPU0_DIMM2_SAA
  RFU2  = TP_CHC_CPU0_DIMM2_FRU_2
  RFU3  = TP_CHC_CPU0_DIMM2_FRU_3
  VSS64  = GND
  DQ2_A  = M_C_CPU0_SA_DQ<2>
  VSS65  = GND
  DQ3_A  = M_C_CPU0_SA_DQ<3>
  VSS66  = GND
  \dqs5_a_c||tdqs5_a_c||dqs5_a_t||tdqs5_a_t\  = M_C_CPU0_SA_DQS_DN<5>
  \dqs5_a_t||tdqs5_a_t\  = M_C_CPU0_SA_DQS_DP<5>
  VSS67  = GND
  DQ6_A  = M_C_CPU0_SA_DQ<6>
  VSS68  = GND
  DQ7_A  = M_C_CPU0_SA_DQ<7>
  VSS69  = GND
  DQ10_A  = M_C_CPU0_SA_DQ<10>
  VSS70  = GND
  DQ11_A  = M_C_CPU0_SA_DQ<11>
  VSS71  = GND
  \dqs6_a_c||tdqs6_a_c||dqs6_a_t||tdqs6_a_t\  = M_C_CPU0_SA_DQS_DN<6>
  \dqs6_a_t||tdqs6_a_t\  = M_C_CPU0_SA_DQS_DP<6>
  VSS72  = GND
  DQ14_A  = M_C_CPU0_SA_DQ<14>
  VSS73  = GND
  DQ15_A  = M_C_CPU0_SA_DQ<15>
  VSS74  = GND
  DQ18_A  = M_C_CPU0_SA_DQ<18>
  VSS75  = GND
  DQ19_A  = M_C_CPU0_SA_DQ<19>
  VSS76  = GND
  \dqs7_a_c||tdqs7_a_c\  = M_C_CPU0_SA_DQS_DN<7>
  \dqs7_a_t||tdqs7_a_t\  = M_C_CPU0_SA_DQS_DP<7>
  VSS77  = GND
  DQ22_A  = M_C_CPU0_SA_DQ<22>
  VSS78  = GND
  DQ23_A  = M_C_CPU0_SA_DQ<23>
  VSS79  = GND
  DQ26_A  = M_C_CPU0_SA_DQ<26>
  VSS80  = GND
  DQ27_A  = M_C_CPU0_SA_DQ<27>
  VSS81  = GND
  \dqs8_a_c||tdqs8_a_c\  = M_C_CPU0_SA_DQS_DN<8>
  \dqs8_a_t||tdqs8_a_t\  = M_C_CPU0_SA_DQS_DP<8>
  VSS82  = GND
  DQ30_A  = M_C_CPU0_SA_DQ<30>
  VSS83  = GND
  DQ31_A  = M_C_CPU0_SA_DQ<31>
  VSS84  = GND
  CB2_A  = M_C_CPU0_SA_CB<2>
  VSS85  = GND
  CB3_A  = M_C_CPU0_SA_CB<3>
  VSS86  = GND
  \dqs9_a_c||tdqs9_a_c\  = M_C_CPU0_SA_DQS_DN<9>
  \dqs9_a_t||tdqs9_a_t\  = M_C_CPU0_SA_DQS_DP<9>
  VSS87  = GND
  CB6_A  = M_C_CPU0_SA_CB<6>
  VSS88  = GND
  CB7_A  = M_C_CPU0_SA_CB<7>
  VSS89  = GND
  RESET_N  = RST_M_CD_CPU0_FPGA_N
  VSS90  = GND
  CS1_A_N  = M_C_CPU0_SA_CS_N<3>
  VSS91  = GND
  CA1_A  = M_C_CPU0_SA_CA<1>
  VSS92  = GND
  CA3_A  = M_C_CPU0_SA_CA<3>
  VSS93  = GND
  CA5_A  = M_C_CPU0_SA_CA<5>
  VSS94  = GND
  CK_T  = M_C_CPU0_CLK_DP<1>
  CK_C  = M_C_CPU0_CLK_DN<1>
  VSS95  = GND
  RFU4  = TP_CHC_CPU0_DIMM2_FRU_4
  CA1_B  = M_C_CPU0_SB_CA<1>
  VSS96  = GND
  CA3_B  = M_C_CPU0_SB_CA<3>
  VSS97  = GND
  CA5_B  = M_C_CPU0_SB_CA<5>
  VSS98  = GND
  PAR_B  = M_C_CPU0_SB_PAR
  VSS99  = GND
  CS1_B_N  = M_C_CPU0_SB_CS_N<3>
  VSS100  = GND
  RFU5  = TP_CHC_CPU0_DIMM2_FRU_5
  RFU6  = TP_CHC_CPU0_DIMM2_FRU_6
  VSS101  = GND
  CB6_B  = M_C_CPU0_SB_CB<6>
  VSS102  = GND
  CB7_B  = M_C_CPU0_SB_CB<7>
  VSS103  = GND
  DQS4_B_C  = M_C_CPU0_SB_DQS_DN<4>
  DQS4_B_T  = M_C_CPU0_SB_DQS_DP<4>
  VSS104  = GND
  CB2_B  = M_C_CPU0_SB_CB<2>
  VSS105  = GND
  CB3_B  = M_C_CPU0_SB_CB<3>
  VSS106  = GND
  DQ2_B  = M_C_CPU0_SB_DQ<2>
  VSS107  = GND
  DQ3_B  = M_C_CPU0_SB_DQ<3>
  VSS108  = GND
  \dqs5_b_c||tdqs5_b_c\  = M_C_CPU0_SB_DQS_DN<5>
  \dqs5_b_t||tdqs5_b_t\  = M_C_CPU0_SB_DQS_DP<5>
  VSS109  = GND
  DQ6_B  = M_C_CPU0_SB_DQ<6>
  VSS110  = GND
  DQ7_B  = M_C_CPU0_SB_DQ<7>
  VSS111  = GND
  DQ10_B  = M_C_CPU0_SB_DQ<10>
  VSS112  = GND
  DQ11_B  = M_C_CPU0_SB_DQ<11>
  VSS113  = GND
  \dqs6_b_c||tdqs6_b_c\  = M_C_CPU0_SB_DQS_DN<6>
  \dqs6_b_t||tdqs6_b_t\  = M_C_CPU0_SB_DQS_DP<6>
  VSS114  = GND
  DQ14_B  = M_C_CPU0_SB_DQ<14>
  VSS115  = GND
  DQ15_B  = M_C_CPU0_SB_DQ<15>
  VSS116  = GND
  DQ18_B  = M_C_CPU0_SB_DQ<18>
  VSS117  = GND
  DQ19_B  = M_C_CPU0_SB_DQ<19>
  VSS118  = GND
  \dqs7_b_c||tdqs7_b_c\  = M_C_CPU0_SB_DQS_DN<7>
  \dqs7_b_t||tdqs7_b_t\  = M_C_CPU0_SB_DQS_DP<7>
  VSS119  = GND
  DQ22_B  = M_C_CPU0_SB_DQ<22>
  VSS120  = GND
  DQ23_B  = M_C_CPU0_SB_DQ<23>
  VSS121  = GND
  DQ26_B  = M_C_CPU0_SB_DQ<26>
  VSS122  = GND
  DQ27_B  = M_C_CPU0_SB_DQ<27>
  VSS123  = GND
  \dqs8_b_c||tdqs8_b_c\  = M_C_CPU0_SB_DQS_DN<8>
  \dqs8_b_t||tdqs8_b_t\  = M_C_CPU0_SB_DQS_DP<8>
  VSS124  = GND
  DQ30_B  = M_C_CPU0_SB_DQ<30>
  VSS125  = GND
  DQ31_B  = M_C_CPU0_SB_DQ<31>
  VSS126  = GND
  G1  = GND
  G2  = GND
  G3  = GND

(kicad_pcb
	(version 20260206)
	(generator "pcbnew")
	(generator_version "10.0")
	(general
		(thickness 1.6)
		(legacy_teardrops no)
	)
	(paper "A4")
	(title_block
		(title "03242023_DA0F0TMBIJ0_F0T_Motherboard_J_brd_V01_OCP.brd")
		(comment 1 "Grand Teton / footprint 3553 of 6105 (J6), pads 229-274 of 291")
	)
	(layers
		(0 "F.Cu" signal "TOP")
		(4 "In1.Cu" signal "GND")
		(6 "In2.Cu" signal "IN1")
		(8 "In3.Cu" signal "GND1")
		(10 "In4.Cu" signal "IN2")
		(12 "In5.Cu" signal "GND2")
		(14 "In6.Cu" signal "IN3")
		(16 "In7.Cu" signal "GND3")
		(18 "In8.Cu" signal "VCC")
		(20 "In9.Cu" signal "VCC1")
		(22 "In10.Cu" signal "GND4")
		(24 "In11.Cu" signal "IN4")
		(26 "In12.Cu" signal "GND5")
		(28 "In13.Cu" signal "IN5")
		(30 "In14.Cu" signal "GND6")
		(32 "In15.Cu" signal "IN6")
		(34 "In16.Cu" signal "GND7")
		(2 "B.Cu" signal "BOTTOM")
		(9 "F.Adhes" user "F.Adhesive")
		(11 "B.Adhes" user "B.Adhesive")
		(13 "F.Paste" user "Package Geometry/Pastemask Top")
		(15 "B.Paste" user "Package Geometry/Pastemask Bottom")
		(5 "F.SilkS" user "Ref Des/Silkscreen Top")
		(7 "B.SilkS" user "Ref Des/Silkscreen Bottom")
		(1 "F.Mask" user "Board Geometry/Soldermask Top")
		(3 "B.Mask" user "Board Geometry/Soldermask Bottom")
		(17 "Dwgs.User" user "User.Drawings")
		(19 "Cmts.User" user "User.Comments")
		(21 "Eco1.User" user "User.Eco1")
		(23 "Eco2.User" user "User.Eco2")
		(25 "Edge.Cuts" user "Board Geometry/Outline")
		(27 "Margin" user)
		(31 "F.CrtYd" user "Package Geometry/Place Bound Top")
		(29 "B.CrtYd" user "Package Geometry/Place Bound Bottom")
		(35 "F.Fab" user "Ref Des/Assembly Top")
		(33 "B.Fab" user "Ref Des/Assembly Bottom")
	)
	(footprint ""
		(layer "F.Cu")
		(at 280.761948 -258.091686)
		(property "Reference" "J6"
			(at -3.683 -81.702148 0)
			(unlocked yes)
			(layer "F.SilkS")
			(effects
				(font
					(size 0.7874 0.5842)
					(thickness 0.1524)
				)
				(justify left)
			)
		)
		(property "Value" ""
			(at 0 0 0)
			(layer "F.Fab")
			(effects
				(font
					(size 1.27 1.27)
				)
			)
		)
		(duplicate_pad_numbers_are_jumpers no)
		(pad "229" smd rect
			(at 2.050034 13.17498 270)
			(size 0.519938 1.4986)
			(layers "F.Cu" "F.Mask" "F.Paste")
			(net "M_C_CPU0_SB_CS_N<3>")
		)
		(pad "230" smd rect
			(at 2.050034 14.025118 270)
			(size 0.519938 1.4986)
			(layers "F.Cu" "F.Mask" "F.Paste")
			(net "GND")
		)
		(pad "231" smd rect
			(at 2.050034 14.875002 270)
			(size 0.519938 1.4986)
			(layers "F.Cu" "F.Mask" "F.Paste")
			(net "TP_CHC_CPU0_DIMM2_FRU_5")
		)
		(pad "232" smd rect
			(at 2.050034 15.724886 270)
			(size 0.519938 1.4986)
			(layers "F.Cu" "F.Mask" "F.Paste")
			(net "TP_CHC_CPU0_DIMM2_FRU_6")
		)
		(pad "233" smd rect
			(at 2.050034 16.575024 270)
			(size 0.519938 1.4986)
			(layers "F.Cu" "F.Mask" "F.Paste")
			(net "GND")
		)
		(pad "234" smd rect
			(at 2.050034 17.424908 270)
			(size 0.519938 1.4986)
			(layers "F.Cu" "F.Mask" "F.Paste")
			(net "M_C_CPU0_SB_CB<6>")
		)
		(pad "235" smd rect
			(at 2.050034 18.275046 270)
			(size 0.519938 1.4986)
			(layers "F.Cu" "F.Mask" "F.Paste")
			(net "GND")
		)
		(pad "236" smd rect
			(at 2.050034 19.12493 270)
			(size 0.519938 1.4986)
			(layers "F.Cu" "F.Mask" "F.Paste")
			(net "M_C_CPU0_SB_CB<7>")
		)
		(pad "237" smd rect
			(at 2.050034 19.975068 270)
			(size 0.519938 1.4986)
			(layers "F.Cu" "F.Mask" "F.Paste")
			(net "GND")
		)
		(pad "238" smd rect
			(at 2.050034 20.824952 270)
			(size 0.519938 1.4986)
			(layers "F.Cu" "F.Mask" "F.Paste")
			(net "M_C_CPU0_SB_DQS_DN<4>")
		)
		(pad "239" smd rect
			(at 2.050034 21.67509 270)
			(size 0.519938 1.4986)
			(layers "F.Cu" "F.Mask" "F.Paste")
			(net "M_C_CPU0_SB_DQS_DP<4>")
		)
		(pad "240" smd rect
			(at 2.050034 22.524974 270)
			(size 0.519938 1.4986)
			(layers "F.Cu" "F.Mask" "F.Paste")
			(net "GND")
		)
		(pad "241" smd rect
			(at 2.050034 23.375112 270)
			(size 0.519938 1.4986)
			(layers "F.Cu" "F.Mask" "F.Paste")
			(net "M_C_CPU0_SB_CB<2>")
		)
		(pad "242" smd rect
			(at 2.050034 24.224996 270)
			(size 0.519938 1.4986)
			(layers "F.Cu" "F.Mask" "F.Paste")
			(net "GND")
		)
		(pad "243" smd rect
			(at 2.050034 25.07488 270)
			(size 0.519938 1.4986)
			(layers "F.Cu" "F.Mask" "F.Paste")
			(net "M_C_CPU0_SB_CB<3>")
		)
		(pad "244" smd rect
			(at 2.050034 25.925018 270)
			(size 0.519938 1.4986)
			(layers "F.Cu" "F.Mask" "F.Paste")
			(net "GND")
		)
		(pad "245" smd rect
			(at 2.050034 26.774902 270)
			(size 0.519938 1.4986)
			(layers "F.Cu" "F.Mask" "F.Paste")
			(net "M_C_CPU0_SB_DQ<2>")
		)
		(pad "246" smd rect
			(at 2.050034 27.62504 270)
			(size 0.519938 1.4986)
			(layers "F.Cu" "F.Mask" "F.Paste")
			(net "GND")
		)
		(pad "247" smd rect
			(at 2.050034 28.474924 270)
			(size 0.519938 1.4986)
			(layers "F.Cu" "F.Mask" "F.Paste")
			(net "M_C_CPU0_SB_DQ<3>")
		)
		(pad "248" smd rect
			(at 2.050034 29.325062 270)
			(size 0.519938 1.4986)
			(layers "F.Cu" "F.Mask" "F.Paste")
			(net "GND")
		)
		(pad "249" smd rect
			(at 2.050034 30.174946 270)
			(size 0.519938 1.4986)
			(layers "F.Cu" "F.Mask" "F.Paste")
			(net "M_C_CPU0_SB_DQS_DN<5>")
		)
		(pad "250" smd rect
			(at 2.050034 31.025084 270)
			(size 0.519938 1.4986)
			(layers "F.Cu" "F.Mask" "F.Paste")
			(net "M_C_CPU0_SB_DQS_DP<5>")
		)
		(pad "251" smd rect
			(at 2.050034 31.874968 270)
			(size 0.519938 1.4986)
			(layers "F.Cu" "F.Mask" "F.Paste")
			(net "GND")
		)
		(pad "252" smd rect
			(at 2.050034 32.725106 270)
			(size 0.519938 1.4986)
			(layers "F.Cu" "F.Mask" "F.Paste")
			(net "M_C_CPU0_SB_DQ<6>")
		)
		(pad "253" smd rect
			(at 2.050034 33.57499 270)
			(size 0.519938 1.4986)
			(layers "F.Cu" "F.Mask" "F.Paste")
			(net "GND")
		)
		(pad "254" smd rect
			(at 2.050034 34.425128 270)
			(size 0.519938 1.4986)
			(layers "F.Cu" "F.Mask" "F.Paste")
			(net "M_C_CPU0_SB_DQ<7>")
		)
		(pad "255" smd rect
			(at 2.050034 35.275012 270)
			(size 0.519938 1.4986)
			(layers "F.Cu" "F.Mask" "F.Paste")
			(net "GND")
		)
		(pad "256" smd rect
			(at 2.050034 36.124896 270)
			(size 0.519938 1.4986)
			(layers "F.Cu" "F.Mask" "F.Paste")
			(net "M_C_CPU0_SB_DQ<10>")
		)
		(pad "257" smd rect
			(at 2.050034 36.975034 270)
			(size 0.519938 1.4986)
			(layers "F.Cu" "F.Mask" "F.Paste")
			(net "GND")
		)
		(pad "258" smd rect
			(at 2.050034 37.824918 270)
			(size 0.519938 1.4986)
			(layers "F.Cu" "F.Mask" "F.Paste")
			(net "M_C_CPU0_SB_DQ<11>")
		)
		(pad "259" smd rect
			(at 2.050034 38.675056 270)
			(size 0.519938 1.4986)
			(layers "F.Cu" "F.Mask" "F.Paste")
			(net "GND")
		)
		(pad "260" smd rect
			(at 2.050034 39.52494 270)
			(size 0.519938 1.4986)
			(layers "F.Cu" "F.Mask" "F.Paste")
			(net "M_C_CPU0_SB_DQS_DN<6>")
		)
		(pad "261" smd rect
			(at 2.050034 40.375078 270)
			(size 0.519938 1.4986)
			(layers "F.Cu" "F.Mask" "F.Paste")
			(net "M_C_CPU0_SB_DQS_DP<6>")
		)
		(pad "262" smd rect
			(at 2.050034 41.224962 270)
			(size 0.519938 1.4986)
			(layers "F.Cu" "F.Mask" "F.Paste")
			(net "GND")
		)
		(pad "263" smd rect
			(at 2.050034 42.0751 270)
			(size 0.519938 1.4986)
			(layers "F.Cu" "F.Mask" "F.Paste")
			(net "M_C_CPU0_SB_DQ<14>")
		)
		(pad "264" smd rect
			(at 2.050034 42.924984 270)
			(size 0.519938 1.4986)
			(layers "F.Cu" "F.Mask" "F.Paste")
			(net "GND")
		)
		(pad "265" smd rect
			(at 2.050034 43.775122 270)
			(size 0.519938 1.4986)
			(layers "F.Cu" "F.Mask" "F.Paste")
			(net "M_C_CPU0_SB_DQ<15>")
		)
		(pad "266" smd rect
			(at 2.050034 44.625006 270)
			(size 0.519938 1.4986)
			(layers "F.Cu" "F.Mask" "F.Paste")
			(net "GND")
		)
		(pad "267" smd rect
			(at 2.050034 45.47489 270)
			(size 0.519938 1.4986)
			(layers "F.Cu" "F.Mask" "F.Paste")
			(net "M_C_CPU0_SB_DQ<18>")
		)
		(pad "268" smd rect
			(at 2.050034 46.325028 270)
			(size 0.519938 1.4986)
			(layers "F.Cu" "F.Mask" "F.Paste")
			(net "GND")
		)
		(pad "269" smd rect
			(at 2.050034 47.174912 270)
			(size 0.519938 1.4986)
			(layers "F.Cu" "F.Mask" "F.Paste")
			(net "M_C_CPU0_SB_DQ<19>")
		)
		(pad "270" smd rect
			(at 2.050034 48.02505 270)
			(size 0.519938 1.4986)
			(layers "F.Cu" "F.Mask" "F.Paste")
			(net "GND")
		)
		(pad "271" smd rect
			(at 2.050034 48.874934 270)
			(size 0.519938 1.4986)
			(layers "F.Cu" "F.Mask" "F.Paste")
			(net "M_C_CPU0_SB_DQS_DN<7>")
		)
		(pad "272" smd rect
			(at 2.050034 49.725072 270)
			(size 0.519938 1.4986)
			(layers "F.Cu" "F.Mask" "F.Paste")
			(net "M_C_CPU0_SB_DQS_DP<7>")
		)
		(pad "273" smd rect
			(at 2.050034 50.574956 270)
			(size 0.519938 1.4986)
			(layers "F.Cu" "F.Mask" "F.Paste")
			(net "GND")
		)
		(pad "274" smd rect
			(at 2.050034 51.425094 270)
			(size 0.519938 1.4986)
			(layers "F.Cu" "F.Mask" "F.Paste")
			(net "M_C_CPU0_SB_DQ<22>")
		)
	)
)
